Created on Valor NPI 9.6 Update 2 - Netlist Compare Summary.
DATE :  14 Mar 2017
TIME :  17:27:59


     MISMATCH SUMMARY REPORT
     -----------------------

Job  : 16347-sc                Job  : 16347-sc
Step : q                       Step : q
Type : CAD                     Type : CURCAD

-----------------------------------------------

 Mismatch Type: shorted


 Total : 0
-----------------------------------------------

 Mismatch Type: broken


 Total : 0
-----------------------------------------------

 Mismatch Type: missing


 Total : 0
-----------------------------------------------

 Mismatch Type: extra


 Total : 0
-----------------------------------------------
